FILE_TYPE = CONNECTIVITY;
{Allegro Design Entry HDL 17.4-2019 S026 (4007227) 1/17/2022}
"PAGE_NUMBER" = 89;
0"NC";
1"GND\g";
2"GND\g";
3"P3V3\g";
4"M_E_CPU0_SB_DQ<31:0>";
5"M_E_CPU0_SA_DQS_DN<9:0>";
6"M_E_CPU0_SA_DQS_DP<9:0>";
7"M_E_CPU0_SA_DQ<31:0>";
8"M_E_CPU0_SB_DQS_DP<9:0>";
9"M_E_CPU0_SB_DQS_DN<9:0>";
10"M_E_CPU0_SA_CB<7:0>";
11"M_E_CPU0_SB_CA<6:0>";
12"M_E_CPU0_SA_CA<6:0>";
13"M_E_CPU0_SB_CB<7:0>";
14"PD_CHE_CPU0_DIMM_SAA";
15"P3V3_AUX\g";
16"I3C_SPD_DDRE_CPU0_SCL";
17"I3C_SPD_DDRE_CPU0_SDA";
18"I3C_SPD_DDRAF_CPU0_SCL";
19"PWRGD_CHE_CPU0_DIMM";
20"I3C_SPD_DDRAF_CPU0_SDA";
21"M_E_CPU0_ALERT_N";
22"M_E_CPU0_SA_DQ<31>";
23"M_E_CPU0_SA_CB<7>";
24"M_E_CPU0_SA_CB<4>";
25"M_E_CPU0_SA_CB<1>";
26"M_E_CPU0_SB_CB<7>";
27"M_E_CPU0_SA_CA<0>";
28"M_E_CPU0_SB_CA<0>";
29"M_E_CPU0_SB_CA<1>";
30"M_E_CPU0_SA_CA<2>";
31"M_E_CPU0_SB_CA<2>";
32"M_E_CPU0_SA_CA<3>";
33"M_E_CPU0_SB_CA<3>";
34"M_E_CPU0_SA_CA<4>";
35"M_E_CPU0_SA_CA<5>";
36"M_E_CPU0_SB_CA<5>";
37"M_E_CPU0_SA_CA<6>";
38"M_E_CPU0_SB_CA<6>";
39"M_E_CPU0_SA_CB<3>";
40"M_E_CPU0_SA_CB<2>";
41"M_E_CPU0_SA_CB<0>";
42"M_E_CPU0_SB_CB<6>";
43"M_E_CPU0_SB_CB<5>";
44"M_E_CPU0_SB_CB<4>";
45"M_E_CPU0_SB_CB<3>";
46"M_E_CPU0_SB_CB<2>";
47"M_E_CPU0_SB_CB<1>";
48"M_E_CPU0_SB_CB<0>";
49"M_E_CPU0_CLK_DN<0>";
50"M_E_CPU0_SB_CS_N<0>";
51"M_E_CPU0_SA_CS_N<1>";
52"M_E_CPU0_SB_CS_N<1>";
53"M_E_CPU0_SA_DQ<30>";
54"M_E_CPU0_SA_DQ<28>";
55"M_E_CPU0_SA_DQ<27>";
56"M_E_CPU0_SA_DQ<26>";
57"M_E_CPU0_SA_DQ<24>";
58"M_E_CPU0_SA_DQ<23>";
59"M_E_CPU0_SA_DQ<21>";
60"M_E_CPU0_SA_DQ<18>";
61"M_E_CPU0_SA_DQ<16>";
62"M_E_CPU0_SA_DQ<15>";
63"M_E_CPU0_SA_DQ<14>";
64"M_E_CPU0_SA_DQ<12>";
65"M_E_CPU0_SA_DQ<11>";
66"M_E_CPU0_SA_DQ<10>";
67"M_E_CPU0_SA_DQ<9>";
68"M_E_CPU0_SA_DQ<8>";
69"M_E_CPU0_SA_DQ<7>";
70"M_E_CPU0_SA_DQ<6>";
71"M_E_CPU0_SA_DQ<5>";
72"M_E_CPU0_SA_DQ<4>";
73"M_E_CPU0_SA_DQ<3>";
74"M_E_CPU0_SA_DQ<2>";
75"M_E_CPU0_SA_DQ<1>";
76"M_E_CPU0_SA_DQ<0>";
77"M_E_CPU0_SB_DQ<31>";
78"M_E_CPU0_SB_DQ<30>";
79"M_E_CPU0_SB_DQ<29>";
80"M_E_CPU0_SB_DQ<28>";
81"M_E_CPU0_SB_DQ<27>";
82"M_E_CPU0_SB_DQ<26>";
83"M_E_CPU0_SB_DQ<25>";
84"M_E_CPU0_SB_DQ<24>";
85"M_E_CPU0_SB_DQ<23>";
86"M_E_CPU0_SB_DQ<22>";
87"M_E_CPU0_SB_DQ<21>";
88"M_E_CPU0_SB_DQ<20>";
89"M_E_CPU0_SB_DQ<19>";
90"M_E_CPU0_SB_DQ<18>";
91"M_E_CPU0_SB_DQ<16>";
92"M_E_CPU0_SB_DQ<15>";
93"M_E_CPU0_SB_DQ<14>";
94"M_E_CPU0_SB_DQ<13>";
95"M_E_CPU0_SB_DQ<12>";
96"M_E_CPU0_SB_DQ<11>";
97"M_E_CPU0_SB_DQ<10>";
98"M_E_CPU0_SB_DQ<8>";
99"M_E_CPU0_SB_DQ<7>";
100"M_E_CPU0_SB_DQ<6>";
101"M_E_CPU0_SB_DQ<5>";
102"M_E_CPU0_SB_DQ<4>";
103"M_E_CPU0_SB_DQ<3>";
104"M_E_CPU0_SB_DQ<2>";
105"M_E_CPU0_SB_DQ<1>";
106"M_E_CPU0_SB_DQ<0>";
107"M_E_CPU0_SA_RSP<0>";
108"M_E_CPU0_SB_RSP<0>";
109"M_E_CPU0_SA_PAR";
110"M_E_CPU0_SB_PAR";
111"M_E_CPU0_SA_DQ<25>";
112"M_E_CPU0_SA_DQ<29>";
113"M_E_CPU0_SA_CA<1>";
114"M_E_CPU0_SB_CA<4>";
115"M_E_CPU0_SA_DQ<22>";
116"M_E_CPU0_SA_DQS_DP<6>";
117"M_E_CPU0_SB_DQS_DP<8>";
118"M_E_CPU0_SB_DQS_DP<7>";
119"M_E_CPU0_SA_DQS_DP<0>";
120"M_E_CPU0_SB_DQS_DN<0>";
121"M_E_CPU0_SB_DQS_DP<0>";
122"M_E_CPU0_SA_DQS_DN<1>";
123"M_E_CPU0_SB_DQS_DN<1>";
124"M_E_CPU0_SB_DQS_DP<1>";
125"M_E_CPU0_SA_DQS_DN<2>";
126"M_E_CPU0_SA_DQS_DP<2>";
127"M_E_CPU0_SB_DQS_DN<2>";
128"M_E_CPU0_SB_DQS_DP<2>";
129"M_E_CPU0_SA_DQS_DN<3>";
130"M_E_CPU0_SB_DQS_DN<3>";
131"M_E_CPU0_SB_DQS_DP<3>";
132"M_E_CPU0_SA_DQS_DN<4>";
133"M_E_CPU0_SA_DQS_DP<4>";
134"M_E_CPU0_SB_DQS_DN<4>";
135"M_E_CPU0_SB_DQS_DP<4>";
136"M_E_CPU0_SA_DQS_DN<5>";
137"M_E_CPU0_SA_DQS_DP<5>";
138"M_E_CPU0_SB_DQS_DN<5>";
139"M_E_CPU0_SB_DQS_DP<5>";
140"M_E_CPU0_SA_DQS_DN<6>";
141"M_E_CPU0_SB_DQS_DN<6>";
142"M_E_CPU0_SB_DQS_DP<6>";
143"M_E_CPU0_SA_DQS_DP<7>";
144"M_E_CPU0_SA_DQ<19>";
145"M_E_CPU0_SA_DQS_DP<3>";
146"M_E_CPU0_SA_CB<5>";
147"M_E_CPU0_SA_CB<6>";
148"M_E_CPU0_CLK_DP<0>";
149"M_E_CPU0_SA_CS_N<0>";
150"M_E_CPU0_SA_DQ<20>";
151"PD_CHE_CPU0_DIMM_SAA";
152"PWRGD_CHAF_CPU0";
153"GND\g";
154"GND\g";
155"P12V_MEM_CPU0\g";
156"M_E_CPU0_SB_DQ<9>";
157"M_E_CPU0_SA_DQS_DP<1>";
158"GND\g";
159"M_E_CPU0_SB_DQS_DN<8>";
160"M_E_CPU0_SB_DQS_DN<7>";
161"M_E_CPU0_SB_DQS_DN<9>";
162"M_E_CPU0_SB_DQS_DP<9>";
163"M_E_CPU0_SA_DQS_DN<0>";
164"M_E_CPU0_SA_DQ<13>";
165"M_E_CPU0_SA_DQ<17>";
166"M_E_CPU0_SA_DQS_DP<9>";
167"M_E_CPU0_SA_DQS_DP<8>";
168"M_E_CPU0_SA_DQS_DN<8>";
169"M_E_CPU0_SA_DQS_DN<9>";
170"M_E_CPU0_SA_DQS_DN<7>";
171"M_E_CPU0_SB_DQ<17>";
172"M_E_CPU0_RESET_N";
%"GND"
"1","(-2300,2175)","0","mstr_symbols","I150";
;
CDS_LIB"mstr_symbols"
SIZE"1B"
VOLTAGE"0.0"
BODY_TYPE"PLUMBING"
HDL_POWER"GND";
"A\NAC"158;
%"GND"
"1","(-500,2000)","0","mstr_symbols","I152";
;
SIZE"1B"
CDS_LIB"mstr_symbols"
VOLTAGE"0.0"
BODY_TYPE"PLUMBING"
HDL_POWER"GND";
"A\NAC"153;
%"VCC_CORE"
"1","(-8775,3650)","0","mstr_symbols","I177";
;
HDL_POWER"P3V3_AUX"
CDS_LIB"mstr_symbols"
VOLTAGE"3.3"
ROOM"PVCCINFAON_CPU0_CTRL";
"A"15;
%"TAP"
"1","(-7975,3425)","2","mstr_standard","I187";
;
CDS_LIB"mstr_standard"
BODY_TYPE"PLUMBING"
HDL_TAP"TRUE";
"B \NAC \NWC"13;
"S \NAC"
BN"1"47;
%"TAP"
"1","(-7975,3475)","2","mstr_standard","I188";
;
CDS_LIB"mstr_standard"
BODY_TYPE"PLUMBING"
HDL_TAP"TRUE";
"B \NAC \NWC"13;
"S \NAC"
BN"2"46;
%"TAP"
"1","(-7975,3375)","2","mstr_standard","I189";
;
CDS_LIB"mstr_standard"
BODY_TYPE"PLUMBING"
HDL_TAP"TRUE";
"B \NAC \NWC"13;
"S \NAC"
BN"0"48;
%"TAP"
"1","(-7975,3525)","2","mstr_standard","I190";
;
CDS_LIB"mstr_standard"
BODY_TYPE"PLUMBING"
HDL_TAP"TRUE";
"B \NAC \NWC"13;
"S \NAC"
BN"3"45;
%"TAP"
"1","(-7975,3575)","2","mstr_standard","I191";
;
CDS_LIB"mstr_standard"
BODY_TYPE"PLUMBING"
HDL_TAP"TRUE";
"B \NAC \NWC"13;
"S \NAC"
BN"4"44;
%"TAP"
"1","(-7975,3625)","2","mstr_standard","I192";
;
CDS_LIB"mstr_standard"
BODY_TYPE"PLUMBING"
HDL_TAP"TRUE";
"B \NAC \NWC"13;
"S \NAC"
BN"5"43;
%"TAP"
"1","(-7975,3725)","2","mstr_standard","I193";
;
CDS_LIB"mstr_standard"
BODY_TYPE"PLUMBING"
HDL_TAP"TRUE";
"B \NAC \NWC"13;
"S \NAC"
BN"7"26;
%"TAP"
"1","(-7975,3675)","2","mstr_standard","I194";
;
CDS_LIB"mstr_standard"
BODY_TYPE"PLUMBING"
HDL_TAP"TRUE";
"B \NAC \NWC"13;
"S \NAC"
BN"6"42;
%"TAP"
"1","(-7975,3925)","2","mstr_standard","I195";
;
CDS_LIB"mstr_standard"
BODY_TYPE"PLUMBING"
HDL_TAP"TRUE";
"B \NAC \NWC"10;
"S \NAC"
BN"2"40;
%"TAP"
"1","(-7975,3875)","2","mstr_standard","I196";
;
CDS_LIB"mstr_standard"
BODY_TYPE"PLUMBING"
HDL_TAP"TRUE";
"B \NAC \NWC"10;
"S \NAC"
BN"1"25;
%"TAP"
"1","(-7975,3825)","2","mstr_standard","I197";
;
CDS_LIB"mstr_standard"
BODY_TYPE"PLUMBING"
HDL_TAP"TRUE";
"B \NAC \NWC"10;
"S \NAC"
BN"0"41;
%"TAP"
"1","(-7975,3975)","2","mstr_standard","I198";
;
CDS_LIB"mstr_standard"
BODY_TYPE"PLUMBING"
HDL_TAP"TRUE";
"B \NAC \NWC"10;
"S \NAC"
BN"3"39;
%"TAP"
"1","(-7975,4025)","2","mstr_standard","I199";
;
CDS_LIB"mstr_standard"
BODY_TYPE"PLUMBING"
HDL_TAP"TRUE";
"B \NAC \NWC"10;
"S \NAC"
BN"4"24;
%"TAP"
"1","(-7975,4075)","2","mstr_standard","I200";
;
CDS_LIB"mstr_standard"
BODY_TYPE"PLUMBING"
HDL_TAP"TRUE";
"B \NAC \NWC"10;
"S \NAC"
BN"5"146;
%"TAP"
"1","(-7975,4125)","2","mstr_standard","I201";
;
CDS_LIB"mstr_standard"
BODY_TYPE"PLUMBING"
HDL_TAP"TRUE";
"B \NAC \NWC"10;
"S \NAC"
BN"6"147;
%"TAP"
"1","(-7975,4175)","2","mstr_standard","I202";
;
CDS_LIB"mstr_standard"
BODY_TYPE"PLUMBING"
HDL_TAP"TRUE";
"B \NAC \NWC"10;
"S \NAC"
BN"7"23;
%"TAP"
"1","(-7975,5025)","2","mstr_standard","I203";
;
CDS_LIB"mstr_standard"
BODY_TYPE"PLUMBING"
HDL_TAP"TRUE";
"B \NAC \NWC"11;
"S \NAC"
BN"3"33;
%"TAP"
"1","(-7975,4925)","2","mstr_standard","I204";
;
CDS_LIB"mstr_standard"
BODY_TYPE"PLUMBING"
HDL_TAP"TRUE";
"B \NAC \NWC"11;
"S \NAC"
BN"1"29;
%"TAP"
"1","(-7975,4875)","2","mstr_standard","I205";
;
CDS_LIB"mstr_standard"
BODY_TYPE"PLUMBING"
HDL_TAP"TRUE";
"B \NAC \NWC"11;
"S \NAC"
BN"0"28;
%"TAP"
"1","(-7975,4975)","2","mstr_standard","I206";
;
CDS_LIB"mstr_standard"
BODY_TYPE"PLUMBING"
HDL_TAP"TRUE";
"B \NAC \NWC"11;
"S \NAC"
BN"2"31;
%"TAP"
"1","(-6275,2425)","0","mstr_standard","I207";
;
CDS_LIB"mstr_standard"
BODY_TYPE"PLUMBING"
HDL_TAP"TRUE";
"B \NAC \NWC"4;
"S \NAC"
BN"1"105;
%"TAP"
"1","(-6275,2375)","0","mstr_standard","I208";
;
CDS_LIB"mstr_standard"
BODY_TYPE"PLUMBING"
HDL_TAP"TRUE";
"B \NAC \NWC"4;
"S \NAC"
BN"0"106;
%"TAP"
"1","(-6275,2475)","0","mstr_standard","I209";
;
CDS_LIB"mstr_standard"
BODY_TYPE"PLUMBING"
HDL_TAP"TRUE";
"B \NAC \NWC"4;
"S \NAC"
BN"2"104;
%"TAP"
"1","(-6275,2525)","0","mstr_standard","I210";
;
CDS_LIB"mstr_standard"
BODY_TYPE"PLUMBING"
HDL_TAP"TRUE";
"B \NAC \NWC"4;
"S \NAC"
BN"3"103;
%"TAP"
"1","(-6275,2575)","0","mstr_standard","I211";
;
CDS_LIB"mstr_standard"
BODY_TYPE"PLUMBING"
HDL_TAP"TRUE";
"B \NAC \NWC"4;
"S \NAC"
BN"4"102;
%"TAP"
"1","(-6275,2625)","0","mstr_standard","I212";
;
CDS_LIB"mstr_standard"
BODY_TYPE"PLUMBING"
HDL_TAP"TRUE";
"B \NAC \NWC"4;
"S \NAC"
BN"5"101;
%"TAP"
"1","(-6275,2725)","0","mstr_standard","I213";
;
CDS_LIB"mstr_standard"
BODY_TYPE"PLUMBING"
HDL_TAP"TRUE";
"B \NAC \NWC"4;
"S \NAC"
BN"7"99;
%"TAP"
"1","(-6275,2675)","0","mstr_standard","I214";
;
CDS_LIB"mstr_standard"
BODY_TYPE"PLUMBING"
HDL_TAP"TRUE";
"B \NAC \NWC"4;
"S \NAC"
BN"6"100;
%"TAP"
"1","(-6275,2775)","0","mstr_standard","I215";
;
CDS_LIB"mstr_standard"
BODY_TYPE"PLUMBING"
HDL_TAP"TRUE";
"B \NAC \NWC"4;
"S \NAC"
BN"8"98;
%"TAP"
"1","(-6275,2825)","0","mstr_standard","I216";
;
CDS_LIB"mstr_standard"
BODY_TYPE"PLUMBING"
HDL_TAP"TRUE";
"B \NAC \NWC"4;
"S \NAC"
BN"9"156;
%"TAP"
"1","(-6275,2875)","0","mstr_standard","I217";
;
CDS_LIB"mstr_standard"
BODY_TYPE"PLUMBING"
HDL_TAP"TRUE";
"B \NAC \NWC"4;
"S \NAC"
BN"10"97;
%"TAP"
"1","(-6275,2925)","0","mstr_standard","I218";
;
CDS_LIB"mstr_standard"
BODY_TYPE"PLUMBING"
HDL_TAP"TRUE";
"B \NAC \NWC"4;
"S \NAC"
BN"11"96;
%"TAP"
"1","(-6275,2975)","0","mstr_standard","I219";
;
CDS_LIB"mstr_standard"
BODY_TYPE"PLUMBING"
HDL_TAP"TRUE";
"B \NAC \NWC"4;
"S \NAC"
BN"12"95;
%"TAP"
"1","(-6275,3025)","0","mstr_standard","I220";
;
CDS_LIB"mstr_standard"
BODY_TYPE"PLUMBING"
HDL_TAP"TRUE";
"B \NAC \NWC"4;
"S \NAC"
BN"13"94;
%"TAP"
"1","(-6275,3125)","0","mstr_standard","I221";
;
CDS_LIB"mstr_standard"
BODY_TYPE"PLUMBING"
HDL_TAP"TRUE";
"B \NAC \NWC"4;
"S \NAC"
BN"15"92;
%"TAP"
"1","(-6275,3075)","0","mstr_standard","I222";
;
CDS_LIB"mstr_standard"
BODY_TYPE"PLUMBING"
HDL_TAP"TRUE";
"B \NAC \NWC"4;
"S \NAC"
BN"14"93;
%"TAP"
"1","(-6275,3275)","0","mstr_standard","I223";
;
CDS_LIB"mstr_standard"
BODY_TYPE"PLUMBING"
HDL_TAP"TRUE";
"B \NAC \NWC"4;
"S \NAC"
BN"18"90;
%"TAP"
"1","(-6275,3225)","0","mstr_standard","I224";
;
CDS_LIB"mstr_standard"
BODY_TYPE"PLUMBING"
HDL_TAP"TRUE";
"B \NAC \NWC"4;
"S \NAC"
BN"17"171;
%"TAP"
"1","(-6275,3175)","0","mstr_standard","I225";
;
CDS_LIB"mstr_standard"
BODY_TYPE"PLUMBING"
HDL_TAP"TRUE";
"B \NAC \NWC"4;
"S \NAC"
BN"16"91;
%"TAP"
"1","(-6275,3425)","0","mstr_standard","I226";
;
CDS_LIB"mstr_standard"
BODY_TYPE"PLUMBING"
HDL_TAP"TRUE";
"B \NAC \NWC"4;
"S \NAC"
BN"21"87;
%"TAP"
"1","(-6275,3475)","0","mstr_standard","I227";
;
CDS_LIB"mstr_standard"
BODY_TYPE"PLUMBING"
HDL_TAP"TRUE";
"B \NAC \NWC"4;
"S \NAC"
BN"22"86;
%"TAP"
"1","(-6275,3375)","0","mstr_standard","I228";
;
CDS_LIB"mstr_standard"
BODY_TYPE"PLUMBING"
HDL_TAP"TRUE";
"B \NAC \NWC"4;
"S \NAC"
BN"20"88;
%"TAP"
"1","(-6275,3525)","0","mstr_standard","I229";
;
CDS_LIB"mstr_standard"
BODY_TYPE"PLUMBING"
HDL_TAP"TRUE";
"B \NAC \NWC"4;
"S \NAC"
BN"23"85;
%"TAP"
"1","(-6275,3325)","0","mstr_standard","I230";
;
CDS_LIB"mstr_standard"
BODY_TYPE"PLUMBING"
HDL_TAP"TRUE";
"B \NAC \NWC"4;
"S \NAC"
BN"19"89;
%"TAP"
"1","(-6275,3675)","0","mstr_standard","I231";
;
CDS_LIB"mstr_standard"
BODY_TYPE"PLUMBING"
HDL_TAP"TRUE";
"B \NAC \NWC"4;
"S \NAC"
BN"26"82;
%"TAP"
"1","(-6275,3725)","0","mstr_standard","I232";
;
CDS_LIB"mstr_standard"
BODY_TYPE"PLUMBING"
HDL_TAP"TRUE";
"B \NAC \NWC"4;
"S \NAC"
BN"27"81;
%"TAP"
"1","(-6275,3625)","0","mstr_standard","I233";
;
CDS_LIB"mstr_standard"
BODY_TYPE"PLUMBING"
HDL_TAP"TRUE";
"B \NAC \NWC"4;
"S \NAC"
BN"25"83;
%"TAP"
"1","(-6275,3775)","0","mstr_standard","I234";
;
CDS_LIB"mstr_standard"
BODY_TYPE"PLUMBING"
HDL_TAP"TRUE";
"B \NAC \NWC"4;
"S \NAC"
BN"28"80;
%"TAP"
"1","(-6275,3575)","0","mstr_standard","I235";
;
CDS_LIB"mstr_standard"
BODY_TYPE"PLUMBING"
HDL_TAP"TRUE";
"B \NAC \NWC"4;
"S \NAC"
BN"24"84;
%"TAP"
"1","(-6275,4025)","0","mstr_standard","I236";
;
CDS_LIB"mstr_standard"
BODY_TYPE"PLUMBING"
HDL_TAP"TRUE";
"B \NAC \NWC"7;
"S \NAC"
BN"0"76;
%"TAP"
"1","(-6275,3875)","0","mstr_standard","I237";
;
CDS_LIB"mstr_standard"
BODY_TYPE"PLUMBING"
HDL_TAP"TRUE";
"B \NAC \NWC"4;
"S \NAC"
BN"30"78;
%"TAP"
"1","(-6275,3925)","0","mstr_standard","I238";
;
CDS_LIB"mstr_standard"
BODY_TYPE"PLUMBING"
HDL_TAP"TRUE";
"B \NAC \NWC"4;
"S \NAC"
BN"31"77;
%"TAP"
"1","(-6275,3825)","0","mstr_standard","I239";
;
CDS_LIB"mstr_standard"
BODY_TYPE"PLUMBING"
HDL_TAP"TRUE";
"B \NAC \NWC"4;
"S \NAC"
BN"29"79;
%"TAP"
"1","(-6275,4125)","0","mstr_standard","I240";
;
CDS_LIB"mstr_standard"
BODY_TYPE"PLUMBING"
HDL_TAP"TRUE";
"B \NAC \NWC"7;
"S \NAC"
BN"2"74;
%"TAP"
"1","(-6275,4075)","0","mstr_standard","I241";
;
CDS_LIB"mstr_standard"
BODY_TYPE"PLUMBING"
HDL_TAP"TRUE";
"B \NAC \NWC"7;
"S \NAC"
BN"1"75;
%"TAP"
"1","(-6275,4175)","0","mstr_standard","I242";
;
CDS_LIB"mstr_standard"
BODY_TYPE"PLUMBING"
HDL_TAP"TRUE";
"B \NAC \NWC"7;
"S \NAC"
BN"3"73;
%"TAP"
"1","(-6275,4225)","0","mstr_standard","I243";
;
CDS_LIB"mstr_standard"
BODY_TYPE"PLUMBING"
HDL_TAP"TRUE";
"B \NAC \NWC"7;
"S \NAC"
BN"4"72;
%"TAP"
"1","(-6275,4275)","0","mstr_standard","I244";
;
CDS_LIB"mstr_standard"
BODY_TYPE"PLUMBING"
HDL_TAP"TRUE";
"B \NAC \NWC"7;
"S \NAC"
BN"5"71;
%"TAP"
"1","(-6275,4375)","0","mstr_standard","I245";
;
CDS_LIB"mstr_standard"
BODY_TYPE"PLUMBING"
HDL_TAP"TRUE";
"B \NAC \NWC"7;
"S \NAC"
BN"7"69;
%"TAP"
"1","(-6275,4325)","0","mstr_standard","I246";
;
CDS_LIB"mstr_standard"
BODY_TYPE"PLUMBING"
HDL_TAP"TRUE";
"B \NAC \NWC"7;
"S \NAC"
BN"6"70;
%"TAP"
"1","(-6275,4425)","0","mstr_standard","I247";
;
CDS_LIB"mstr_standard"
BODY_TYPE"PLUMBING"
HDL_TAP"TRUE";
"B \NAC \NWC"7;
"S \NAC"
BN"8"68;
%"TAP"
"1","(-6275,4475)","0","mstr_standard","I248";
;
CDS_LIB"mstr_standard"
BODY_TYPE"PLUMBING"
HDL_TAP"TRUE";
"B \NAC \NWC"7;
"S \NAC"
BN"9"67;
%"TAP"
"1","(-6275,4525)","0","mstr_standard","I249";
;
CDS_LIB"mstr_standard"
BODY_TYPE"PLUMBING"
HDL_TAP"TRUE";
"B \NAC \NWC"7;
"S \NAC"
BN"10"66;
%"TAP"
"1","(-6275,4725)","0","mstr_standard","I250";
;
CDS_LIB"mstr_standard"
BODY_TYPE"PLUMBING"
HDL_TAP"TRUE";
"B \NAC \NWC"7;
"S \NAC"
BN"14"63;
%"TAP"
"1","(-6275,4775)","0","mstr_standard","I251";
;
CDS_LIB"mstr_standard"
BODY_TYPE"PLUMBING"
HDL_TAP"TRUE";
"B \NAC \NWC"7;
"S \NAC"
BN"15"62;
%"TAP"
"1","(-6275,4675)","0","mstr_standard","I252";
;
CDS_LIB"mstr_standard"
BODY_TYPE"PLUMBING"
HDL_TAP"TRUE";
"B \NAC \NWC"7;
"S \NAC"
BN"13"164;
%"TAP"
"1","(-6275,4625)","0","mstr_standard","I253";
;
CDS_LIB"mstr_standard"
BODY_TYPE"PLUMBING"
HDL_TAP"TRUE";
"B \NAC \NWC"7;
"S \NAC"
BN"12"64;
%"TAP"
"1","(-6275,4575)","0","mstr_standard","I254";
;
CDS_LIB"mstr_standard"
BODY_TYPE"PLUMBING"
HDL_TAP"TRUE";
"B \NAC \NWC"7;
"S \NAC"
BN"11"65;
%"TAP"
"1","(-6275,4875)","0","mstr_standard","I255";
;
CDS_LIB"mstr_standard"
BODY_TYPE"PLUMBING"
HDL_TAP"TRUE";
"B \NAC \NWC"7;
"S \NAC"
BN"17"165;
%"TAP"
"1","(-6275,4925)","0","mstr_standard","I256";
;
CDS_LIB"mstr_standard"
BODY_TYPE"PLUMBING"
HDL_TAP"TRUE";
"B \NAC \NWC"7;
"S \NAC"
BN"18"60;
%"TAP"
"1","(-6275,4825)","0","mstr_standard","I257";
;
CDS_LIB"mstr_standard"
BODY_TYPE"PLUMBING"
HDL_TAP"TRUE";
"B \NAC \NWC"7;
"S \NAC"
BN"16"61;
%"TAP"
"1","(-6275,5025)","0","mstr_standard","I258";
;
CDS_LIB"mstr_standard"
BODY_TYPE"PLUMBING"
HDL_TAP"TRUE";
"B \NAC \NWC"7;
"S \NAC"
BN"20"150;
%"TAP"
"1","(-6275,4975)","0","mstr_standard","I259";
;
CDS_LIB"mstr_standard"
BODY_TYPE"PLUMBING"
HDL_TAP"TRUE";
"B \NAC \NWC"7;
"S \NAC"
BN"19"144;
%"TAP"
"1","(-7975,5175)","2","mstr_standard","I263";
;
CDS_LIB"mstr_standard"
BODY_TYPE"PLUMBING"
HDL_TAP"TRUE";
"B \NAC \NWC"11;
"S \NAC"
BN"6"38;
%"TAP"
"1","(-7975,5075)","2","mstr_standard","I264";
;
CDS_LIB"mstr_standard"
BODY_TYPE"PLUMBING"
HDL_TAP"TRUE";
"B \NAC \NWC"11;
"S \NAC"
BN"4"114;
%"TAP"
"1","(-7975,5125)","2","mstr_standard","I265";
;
CDS_LIB"mstr_standard"
BODY_TYPE"PLUMBING"
HDL_TAP"TRUE";
"B \NAC \NWC"11;
"S \NAC"
BN"5"36;
%"TAP"
"1","(-7975,5275)","2","mstr_standard","I266";
;
CDS_LIB"mstr_standard"
BODY_TYPE"PLUMBING"
HDL_TAP"TRUE";
"B \NAC \NWC"12;
"S \NAC"
BN"0"27;
%"TAP"
"1","(-7975,5325)","2","mstr_standard","I267";
;
CDS_LIB"mstr_standard"
BODY_TYPE"PLUMBING"
HDL_TAP"TRUE";
"B \NAC \NWC"12;
"S \NAC"
BN"1"113;
%"TAP"
"1","(-7975,5375)","2","mstr_standard","I268";
;
CDS_LIB"mstr_standard"
BODY_TYPE"PLUMBING"
HDL_TAP"TRUE";
"B \NAC \NWC"12;
"S \NAC"
BN"2"30;
%"TAP"
"1","(-7975,5425)","2","mstr_standard","I269";
;
CDS_LIB"mstr_standard"
BODY_TYPE"PLUMBING"
HDL_TAP"TRUE";
"B \NAC \NWC"12;
"S \NAC"
BN"3"32;
%"TAP"
"1","(-7975,5525)","2","mstr_standard","I270";
;
CDS_LIB"mstr_standard"
BODY_TYPE"PLUMBING"
HDL_TAP"TRUE";
"B \NAC \NWC"12;
"S \NAC"
BN"5"35;
%"TAP"
"1","(-7975,5475)","2","mstr_standard","I271";
;
CDS_LIB"mstr_standard"
BODY_TYPE"PLUMBING"
HDL_TAP"TRUE";
"B \NAC \NWC"12;
"S \NAC"
BN"4"34;
%"TAP"
"1","(-7975,5575)","2","mstr_standard","I272";
;
CDS_LIB"mstr_standard"
BODY_TYPE"PLUMBING"
HDL_TAP"TRUE";
"B \NAC \NWC"12;
"S \NAC"
BN"6"37;
%"TAP"
"1","(-6275,5175)","0","mstr_standard","I273";
;
CDS_LIB"mstr_standard"
BODY_TYPE"PLUMBING"
HDL_TAP"TRUE";
"B \NAC \NWC"7;
"S \NAC"
BN"23"58;
%"TAP"
"1","(-6275,5075)","0","mstr_standard","I274";
;
CDS_LIB"mstr_standard"
BODY_TYPE"PLUMBING"
HDL_TAP"TRUE";
"B \NAC \NWC"7;
"S \NAC"
BN"21"59;
%"TAP"
"1","(-6275,5125)","0","mstr_standard","I275";
;
CDS_LIB"mstr_standard"
BODY_TYPE"PLUMBING"
HDL_TAP"TRUE";
"B \NAC \NWC"7;
"S \NAC"
BN"22"115;
%"TAP"
"1","(-6275,5225)","0","mstr_standard","I276";
;
CDS_LIB"mstr_standard"
BODY_TYPE"PLUMBING"
HDL_TAP"TRUE";
"B \NAC \NWC"7;
"S \NAC"
BN"24"57;
%"TAP"
"1","(-6275,5275)","0","mstr_standard","I277";
;
CDS_LIB"mstr_standard"
BODY_TYPE"PLUMBING"
HDL_TAP"TRUE";
"B \NAC \NWC"7;
"S \NAC"
BN"25"111;
%"TAP"
"1","(-6275,5325)","0","mstr_standard","I278";
;
CDS_LIB"mstr_standard"
BODY_TYPE"PLUMBING"
HDL_TAP"TRUE";
"B \NAC \NWC"7;
"S \NAC"
BN"26"56;
%"TAP"
"1","(-6275,5575)","0","mstr_standard","I279";
;
CDS_LIB"mstr_standard"
BODY_TYPE"PLUMBING"
HDL_TAP"TRUE";
"B \NAC \NWC"7;
"S \NAC"
BN"31"22;
%"TAP"
"1","(-6275,5375)","0","mstr_standard","I280";
;
CDS_LIB"mstr_standard"
BODY_TYPE"PLUMBING"
HDL_TAP"TRUE";
"B \NAC \NWC"7;
"S \NAC"
BN"27"55;
%"TAP"
"1","(-6275,5425)","0","mstr_standard","I281";
;
CDS_LIB"mstr_standard"
BODY_TYPE"PLUMBING"
HDL_TAP"TRUE";
"B \NAC \NWC"7;
"S \NAC"
BN"28"54;
%"TAP"
"1","(-6275,5525)","0","mstr_standard","I282";
;
CDS_LIB"mstr_standard"
BODY_TYPE"PLUMBING"
HDL_TAP"TRUE";
"B \NAC \NWC"7;
"S \NAC"
BN"30"53;
%"TAP"
"1","(-6275,5475)","0","mstr_standard","I283";
;
CDS_LIB"mstr_standard"
BODY_TYPE"PLUMBING"
HDL_TAP"TRUE";
"B \NAC \NWC"7;
"S \NAC"
BN"29"112;
%"Q_RES"
"2","(-6650,1425)","0","pure_quanta","I331";
;
LOCATION"R5"
SEC"1"
PACK_TYPE"0402LF"
VALUE"54.9K"
TOLERANCE"1%"
MATERIAL"CHIP"
WATTAGE"1/16W"
SEC_TYPE"0402LF"
CDS_LIB"pure_quanta"
BOM_COST"MEM"
PART_NUMBER"CS35492FB03";
"A"
$PN"1"
XNET_PINS"3"151;
"B"
$PN"2"
XNET_PINS"2"1;
%"GND"
"1","(-6650,1200)","0","mstr_symbols","I332";
;
SIZE"1B"
CDS_LIB"mstr_symbols"
BOM_COST"MEM"
VOLTAGE"0.0"
BODY_TYPE"PLUMBING"
HDL_POWER"GND";
"A\NAC"1;
%"SCONN288_DDR506112002KQ"
"1","(-7125,3825)","0","pure_quanta","I348";
;
LOCATION"J21"
$SEC"1"
CDS_SEC"1"
PART_TYPE"SMLF"
VALUE"SCONN288_DDR506112002KQ"
MATERIAL"IO"
CDS_LMAN_SYM_OUTLINE"-450,1900,450,-1850"
NEEDS_NO_SIZE"TRUE"
CDS_LIB"pure_quanta"
PART_NUMBER"DFHST8FS479";
"PWR_GOOD||FAIL_N"
$PN"147"19;
"DQ31_A"
$PN"194"22;
"CB7_A"
$PN"205"23;
"CB4_A"
$PN"58"24;
"CB1_A"
$PN"53"25;
"CB7_B"
$PN"236"26;
"ALERT_N \B"
$PN"62"21;
"CA0_A"
$PN"66"27;
"CA0_B"
$PN"76"28;
"CA1_A"
$PN"211"113;
"CA1_B"
$PN"221"29;
"CA2_A"
$PN"68"30;
"CA2_B"
$PN"78"31;
"CA3_A"
$PN"213"32;
"CA3_B"
$PN"223"33;
"CA4_A"
$PN"70"34;
"CA4_B"
$PN"80"114;
"CA5_A"
$PN"215"35;
"CA5_B"
$PN"225"36;
"CA6_A"
$PN"72"37;
"CA6_B"
$PN"82"38;
"CB6_A"
$PN"203"147;
"CB5_A"
$PN"60"146;
"CB3_A"
$PN"198"39;
"CB2_A"
$PN"196"40;
"CB0_A"
$PN"51"41;
"CB6_B"
$PN"234"42;
"CB5_B"
$PN"91"43;
"CB4_B"
$PN"89"44;
"CB3_B"
$PN"243"45;
"CB2_B"
$PN"241"46;
"CB1_B"
$PN"98"47;
"CB0_B"
$PN"96"48;
"CK_C \B"
$PN"218"49;
"CK_T"
$PN"217"148;
"CS0_A_N"
$PN"64"149;
"CS0_B_N"
$PN"84"50;
"CS1_A_N"
$PN"209"51;
"CS1_B_N"
$PN"229"52;
"DQ30_A"
$PN"192"53;
"DQ29_A"
$PN"49"112;
"DQ28_A"
$PN"47"54;
"DQ27_A"
$PN"187"55;
"DQ26_A"
$PN"185"56;
"DQ25_A"
$PN"42"111;
"DQ24_A"
$PN"40"57;
"DQ23_A"
$PN"183"58;
"DQ22_A"
$PN"181"115;
"DQ21_A"
$PN"38"59;
"DQ20_A"
$PN"36"150;
"DQ19_A"
$PN"176"144;
"DQ18_A"
$PN"174"60;
"DQ17_A"
$PN"31"165;
"DQ16_A"
$PN"29"61;
"DQ15_A"
$PN"172"62;
"DQ14_A"
$PN"170"63;
"DQ13_A"
$PN"27"164;
"DQ12_A"
$PN"25"64;
"DQ11_A"
$PN"165"65;
"DQ10_A"
$PN"163"66;
"DQ9_A"
$PN"20"67;
"DQ8_A"
$PN"18"68;
"DQ7_A"
$PN"161"69;
"DQ6_A"
$PN"159"70;
"DQ5_A"
$PN"16"71;
"DQ4_A"
$PN"14"72;
"DQ3_A"
$PN"154"73;
"DQ2_A"
$PN"152"74;
"DQ1_A"
$PN"9"75;
"DQ0_A"
$PN"7"76;
"DQ31_B"
$PN"287"77;
"DQ30_B"
$PN"285"78;
"DQ29_B"
$PN"142"79;
"DQ28_B"
$PN"140"80;
"DQ27_B"
$PN"280"81;
"DQ26_B"
$PN"278"82;
"DQ25_B"
$PN"135"83;
"DQ24_B"
$PN"133"84;
"DQ23_B"
$PN"276"85;
"DQ22_B"
$PN"274"86;
"DQ21_B"
$PN"131"87;
"DQ20_B"
$PN"129"88;
"DQ19_B"
$PN"269"89;
"DQ18_B"
$PN"267"90;
"DQ17_B"
$PN"124"171;
"DQ16_B"
$PN"122"91;
"DQ15_B"
$PN"265"92;
"DQ14_B"
$PN"263"93;
"DQ13_B"
$PN"120"94;
"DQ12_B"
$PN"118"95;
"DQ11_B"
$PN"258"96;
"DQ10_B"
$PN"256"97;
"DQ9_B"
$PN"113"156;
"DQ8_B"
$PN"111"98;
"DQ7_B"
$PN"254"99;
"DQ6_B"
$PN"252"100;
"DQ5_B"
$PN"109"101;
"DQ4_B"
$PN"107"102;
"DQ3_B"
$PN"247"103;
"DQ2_B"
$PN"245"104;
"DQ1_B"
$PN"102"105;
"DQ0_B"
$PN"100"106;
"HAS"
$PN"148"14;
"HSCL"
$PN"4"16;
"HSDA"
$PN"5"17;
"LBD||RSP_A_N"
$PN"86"107;
"LBS||RSP_B_N"
$PN"87"108;
"PAR_A"
$PN"74"109;
"PAR_B"
$PN"227"110;
"RESET_N \B"
$PN"207"172;
"RFU6"
$PN"232"0;
"RFU5"
$PN"231"0;
"RFU4"
$PN"220"0;
"RFU3"
$PN"150"0;
"RFU2"
$PN"149"0;
"RFU1"
$PN"144"0;
"RFU0"
$PN"2"0;
"VIN_MGMT"
$PN"3"15;
%"SCONN288_DDR506112002KQ"
"3","(-1400,3925)","0","pure_quanta","I350";
;
LOCATION"J21"
$SEC"3"
CDS_SEC"3"
PART_TYPE"SMLF"
VALUE"SCONN288_DDR506112002KQ"
MATERIAL"IO"
CDS_LMAN_SYM_OUTLINE"-450,1800,450,-1750"
NEEDS_NO_SIZE"TRUE"
CDS_LIB"pure_quanta"
PART_NUMBER"DFHST8FS479";
"G3"
$PN"G3"153;
"G2"
$PN"G2"153;
"G1"
$PN"G1"153;
"VSS62"
$PN"141"153;
"VSS61"
$PN"139"153;
"VSS60"
$PN"136"153;
"VSS58"
$PN"132"153;
"VSS104"
$PN"240"158;
"VSS102"
$PN"235"158;
"VSS100"
$PN"230"158;
"VIN_BULK2"
$PN"146"155;
"VIN_BULK1"
$PN"145"155;
"VIN_BULK0"
$PN"1"155;
"VSS126"
$PN"288"158;
"VSS125"
$PN"286"158;
"VSS124"
$PN"284"158;
"VSS123"
$PN"281"158;
"VSS122"
$PN"279"158;
"VSS121"
$PN"277"158;
"VSS120"
$PN"275"158;
"VSS119"
$PN"273"158;
"VSS118"
$PN"270"158;
"VSS117"
$PN"268"158;
"VSS116"
$PN"266"158;
"VSS115"
$PN"264"158;
"VSS114"
$PN"262"158;
"VSS113"
$PN"259"158;
"VSS112"
$PN"257"158;
"VSS111"
$PN"255"158;
"VSS110"
$PN"253"158;
"VSS109"
$PN"251"158;
"VSS108"
$PN"248"158;
"VSS107"
$PN"246"158;
"VSS106"
$PN"244"158;
"VSS105"
$PN"242"158;
"VSS103"
$PN"237"158;
"VSS101"
$PN"233"158;
"VSS99"
$PN"228"158;
"VSS98"
$PN"226"158;
"VSS97"
$PN"224"158;
"VSS96"
$PN"222"158;
"VSS95"
$PN"219"158;
"VSS94"
$PN"216"158;
"VSS93"
$PN"214"158;
"VSS92"
$PN"212"158;
"VSS91"
$PN"210"158;
"VSS90"
$PN"208"158;
"VSS89"
$PN"206"158;
"VSS88"
$PN"204"158;
"VSS87"
$PN"202"158;
"VSS86"
$PN"199"158;
"VSS85"
$PN"197"158;
"VSS84"
$PN"195"158;
"VSS83"
$PN"193"158;
"VSS82"
$PN"191"158;
"VSS81"
$PN"188"158;
"VSS80"
$PN"186"158;
"VSS79"
$PN"184"158;
"VSS78"
$PN"182"158;
"VSS77"
$PN"180"158;
"VSS76"
$PN"177"158;
"VSS75"
$PN"175"158;
"VSS74"
$PN"173"158;
"VSS73"
$PN"171"158;
"VSS72"
$PN"169"158;
"VSS71"
$PN"166"158;
"VSS70"
$PN"164"158;
"VSS69"
$PN"162"158;
"VSS68"
$PN"160"158;
"VSS67"
$PN"158"158;
"VSS66"
$PN"155"158;
"VSS65"
$PN"153"158;
"VSS64"
$PN"151"158;
"VSS63"
$PN"143"153;
"VSS59"
$PN"134"153;
"VSS57"
$PN"130"153;
"VSS56"
$PN"128"153;
"VSS55"
$PN"125"153;
"VSS54"
$PN"123"153;
"VSS53"
$PN"121"153;
"VSS52"
$PN"119"153;
"VSS51"
$PN"117"153;
"VSS50"
$PN"114"153;
"VSS49"
$PN"112"153;
"VSS48"
$PN"110"153;
"VSS47"
$PN"108"153;
"VSS46"
$PN"106"153;
"VSS45"
$PN"103"153;
"VSS44"
$PN"101"153;
"VSS43"
$PN"99"153;
"VSS42"
$PN"97"153;
"VSS41"
$PN"95"153;
"VSS40"
$PN"92"153;
"VSS39"
$PN"90"153;
"VSS38"
$PN"88"153;
"VSS37"
$PN"85"153;
"VSS36"
$PN"83"153;
"VSS35"
$PN"81"153;
"VSS34"
$PN"79"153;
"VSS33"
$PN"77"153;
"VSS32"
$PN"75"153;
"VSS31"
$PN"73"153;
"VSS30"
$PN"71"153;
"VSS29"
$PN"69"153;
"VSS28"
$PN"67"153;
"VSS27"
$PN"65"153;
"VSS26"
$PN"63"153;
"VSS25"
$PN"61"153;
"VSS24"
$PN"59"153;
"VSS23"
$PN"57"153;
"VSS22"
$PN"54"153;
"VSS21"
$PN"52"153;
"VSS20"
$PN"50"153;
"VSS19"
$PN"48"153;
"VSS18"
$PN"46"153;
"VSS17"
$PN"43"153;
"VSS16"
$PN"41"153;
"VSS15"
$PN"39"153;
"VSS14"
$PN"37"153;
"VSS13"
$PN"35"153;
"VSS12"
$PN"32"153;
"VSS11"
$PN"30"153;
"VSS10"
$PN"28"153;
"VSS9"
$PN"26"153;
"VSS8"
$PN"24"153;
"VSS7"
$PN"21"153;
"VSS6"
$PN"19"153;
"VSS5"
$PN"17"153;
"VSS4"
$PN"15"153;
"VSS3"
$PN"13"153;
"VSS2"
$PN"10"153;
"VSS1"
$PN"8"153;
"VSS0"
$PN"6"153;
%"GND"
"1","(-8875,3175)","0","mstr_symbols","I359";
;
BOM_COST"MEM"
SIZE"1B"
CDS_LIB"mstr_symbols"
VOLTAGE"0"
ROOM"MEM_EFGH_DECOUPLING_CAPS"
BODY_TYPE"PLUMBING"
HDL_POWER"GND";
"A\NAC"2;
%"Q_CAP"
"1","(-8875,3400)","2","pure_quanta","I360";
;
LOCATION"C104"
$SEC"1"
CDS_SEC"1"
MATERIAL"X7R"
TOLERANCE"10%"
VOLTAGE"25V"
PACK_TYPE"0402"
VALUE"0.1UF"
CDS_LIB"pure_quanta"
BOM_COST"MEM"
ROOM""
PART_NUMBER"CH4104K1B00";
"B"
$PN"2"2;
"A"
$PN"1"15;
%"Q_RES"
"1","(-8725,2325)","2","pure_quanta","I362";
;
LOCATION"R295"
$SEC"1"
CDS_SEC"1"
VALUE"1K"
TOLERANCE"1%"
CDS_LIB"pure_quanta"
BOM_COST"MEM"
WATTAGE"1/16W"
MATERIAL"CHIP"
PACK_TYPE"0402LF"
ROOM""
PART_NUMBER"CS21002FB06";
"B"
$PN"2"152;
"A"
$PN"1"19;
%"VCC_CORE"
"1","(-8600,2650)","0","mstr_symbols","I363";
;
HDL_POWER"P3V3"
CDS_LIB"mstr_symbols"
VOLTAGE"3.3"
ROOM"PVCCINFAON_CPU0_CTRL";
"A"3;
%"Q_RES"
"2","(-8600,2475)","0","pure_quanta","I364";
;
LOCATION"R93"
$SEC"1"
CDS_SEC"1"
WATTAGE"1/16W"
TOLERANCE"1%"
MATERIAL"EMPTY"
VALUE"1K"
PACK_TYPE"0402LF"
CDS_LIB"pure_quanta"
BOM_COST"MEM"
ROOM""
PART_NUMBER"CS21002FB06";
"A"
$PN"1"3;
"B"
$PN"2"19;
%"TAP"
"1","(-3475,4625)","0","mstr_standard","I368";
;
CDS_LIB"mstr_standard"
BODY_TYPE"PLUMBING"
HDL_TAP"TRUE";
"B \NAC \NWC"5;
"S \NAC"
BN"9"169;
%"TAP"
"1","(-3675,4575)","0","mstr_standard","I369";
;
CDS_LIB"mstr_standard"
BODY_TYPE"PLUMBING"
HDL_TAP"TRUE";
"B \NAC \NWC"6;
"S \NAC"
BN"8"167;
%"TAP"
"1","(-3675,4675)","0","mstr_standard","I370";
;
CDS_LIB"mstr_standard"
BODY_TYPE"PLUMBING"
HDL_TAP"TRUE";
"B \NAC \NWC"6;
"S \NAC"
BN"9"166;
%"TAP"
"1","(-3475,4525)","0","mstr_standard","I371";
;
CDS_LIB"mstr_standard"
BODY_TYPE"PLUMBING"
HDL_TAP"TRUE";
"B \NAC \NWC"5;
"S \NAC"
BN"8"168;
%"TAP"
"1","(-3475,4325)","0","mstr_standard","I372";
;
CDS_LIB"mstr_standard"
BODY_TYPE"PLUMBING"
HDL_TAP"TRUE";
"B \NAC \NWC"5;
"S \NAC"
BN"6"140;
%"TAP"
"1","(-3475,4425)","0","mstr_standard","I373";
;
CDS_LIB"mstr_standard"
BODY_TYPE"PLUMBING"
HDL_TAP"TRUE";
"B \NAC \NWC"5;
"S \NAC"
BN"7"170;
%"TAP"
"1","(-3675,4475)","0","mstr_standard","I374";
;
CDS_LIB"mstr_standard"
BODY_TYPE"PLUMBING"
HDL_TAP"TRUE";
"B \NAC \NWC"6;
"S \NAC"
BN"7"143;
%"TAP"
"1","(-3675,4375)","0","mstr_standard","I375";
;
CDS_LIB"mstr_standard"
BODY_TYPE"PLUMBING"
HDL_TAP"TRUE";
"B \NAC \NWC"6;
"S \NAC"
BN"6"116;
%"TAP"
"1","(-3475,4125)","0","mstr_standard","I378";
;
CDS_LIB"mstr_standard"
BODY_TYPE"PLUMBING"
HDL_TAP"TRUE";
"B \NAC \NWC"5;
"S \NAC"
BN"4"132;
%"TAP"
"1","(-3475,4225)","0","mstr_standard","I379";
;
CDS_LIB"mstr_standard"
BODY_TYPE"PLUMBING"
HDL_TAP"TRUE";
"B \NAC \NWC"5;
"S \NAC"
BN"5"136;
%"TAP"
"1","(-3675,4175)","0","mstr_standard","I380";
;
CDS_LIB"mstr_standard"
BODY_TYPE"PLUMBING"
HDL_TAP"TRUE";
"B \NAC \NWC"6;
"S \NAC"
BN"4"133;
%"TAP"
"1","(-3675,4275)","0","mstr_standard","I381";
;
CDS_LIB"mstr_standard"
BODY_TYPE"PLUMBING"
HDL_TAP"TRUE";
"B \NAC \NWC"6;
"S \NAC"
BN"5"137;
%"TAP"
"1","(-3675,4075)","0","mstr_standard","I382";
;
CDS_LIB"mstr_standard"
BODY_TYPE"PLUMBING"
HDL_TAP"TRUE";
"B \NAC \NWC"6;
"S \NAC"
BN"3"145;
%"TAP"
"1","(-3475,3925)","0","mstr_standard","I383";
;
CDS_LIB"mstr_standard"
BODY_TYPE"PLUMBING"
HDL_TAP"TRUE";
"B \NAC \NWC"5;
"S \NAC"
BN"2"125;
%"TAP"
"1","(-3475,4025)","0","mstr_standard","I384";
;
CDS_LIB"mstr_standard"
BODY_TYPE"PLUMBING"
HDL_TAP"TRUE";
"B \NAC \NWC"5;
"S \NAC"
BN"3"129;
%"TAP"
"1","(-3475,3825)","0","mstr_standard","I385";
;
CDS_LIB"mstr_standard"
BODY_TYPE"PLUMBING"
HDL_TAP"TRUE";
"B \NAC \NWC"5;
"S \NAC"
BN"1"122;
%"TAP"
"1","(-3675,3975)","0","mstr_standard","I386";
;
CDS_LIB"mstr_standard"
BODY_TYPE"PLUMBING"
HDL_TAP"TRUE";
"B \NAC \NWC"6;
"S \NAC"
BN"2"126;
%"TAP"
"1","(-3675,3875)","0","mstr_standard","I387";
;
CDS_LIB"mstr_standard"
BODY_TYPE"PLUMBING"
HDL_TAP"TRUE";
"B \NAC \NWC"6;
"S \NAC"
BN"1"157;
%"TAP"
"1","(-3475,3575)","0","mstr_standard","I388";
;
CDS_LIB"mstr_standard"
BODY_TYPE"PLUMBING"
HDL_TAP"TRUE";
"B \NAC \NWC"9;
"S \NAC"
BN"9"161;
%"TAP"
"1","(-3475,3725)","0","mstr_standard","I389";
;
CDS_LIB"mstr_standard"
BODY_TYPE"PLUMBING"
HDL_TAP"TRUE";
"B \NAC \NWC"5;
"S \NAC"
BN"0"163;
%"TAP"
"1","(-3675,3775)","0","mstr_standard","I390";
;
CDS_LIB"mstr_standard"
BODY_TYPE"PLUMBING"
HDL_TAP"TRUE";
"B \NAC \NWC"6;
"S \NAC"
BN"0"119;
%"TAP"
"1","(-3675,3625)","0","mstr_standard","I391";
;
CDS_LIB"mstr_standard"
BODY_TYPE"PLUMBING"
HDL_TAP"TRUE";
"B \NAC \NWC"8;
"S \NAC"
BN"9"162;
%"TAP"
"1","(-3475,3475)","0","mstr_standard","I392";
;
CDS_LIB"mstr_standard"
BODY_TYPE"PLUMBING"
HDL_TAP"TRUE";
"B \NAC \NWC"9;
"S \NAC"
BN"8"159;
%"TAP"
"1","(-3475,3275)","0","mstr_standard","I393";
;
CDS_LIB"mstr_standard"
BODY_TYPE"PLUMBING"
HDL_TAP"TRUE";
"B \NAC \NWC"9;
"S \NAC"
BN"6"141;
%"TAP"
"1","(-3475,3375)","0","mstr_standard","I394";
;
CDS_LIB"mstr_standard"
BODY_TYPE"PLUMBING"
HDL_TAP"TRUE";
"B \NAC \NWC"9;
"S \NAC"
BN"7"160;
%"TAP"
"1","(-3675,3525)","0","mstr_standard","I395";
;
CDS_LIB"mstr_standard"
BODY_TYPE"PLUMBING"
HDL_TAP"TRUE";
"B \NAC \NWC"8;
"S \NAC"
BN"8"117;
%"TAP"
"1","(-3675,3425)","0","mstr_standard","I396";
;
CDS_LIB"mstr_standard"
BODY_TYPE"PLUMBING"
HDL_TAP"TRUE";
"B \NAC \NWC"8;
"S \NAC"
BN"7"118;
%"TAP"
"1","(-3675,3325)","0","mstr_standard","I397";
;
CDS_LIB"mstr_standard"
BODY_TYPE"PLUMBING"
HDL_TAP"TRUE";
"B \NAC \NWC"8;
"S \NAC"
BN"6"142;
%"TAP"
"1","(-3475,3075)","0","mstr_standard","I398";
;
CDS_LIB"mstr_standard"
BODY_TYPE"PLUMBING"
HDL_TAP"TRUE";
"B \NAC \NWC"9;
"S \NAC"
BN"4"134;
%"TAP"
"1","(-3475,3175)","0","mstr_standard","I399";
;
CDS_LIB"mstr_standard"
BODY_TYPE"PLUMBING"
HDL_TAP"TRUE";
"B \NAC \NWC"9;
"S \NAC"
BN"5"138;
%"TAP"
"1","(-3675,3225)","0","mstr_standard","I400";
;
CDS_LIB"mstr_standard"
BODY_TYPE"PLUMBING"
HDL_TAP"TRUE";
"B \NAC \NWC"8;
"S \NAC"
BN"5"139;
%"TAP"
"1","(-3675,3025)","0","mstr_standard","I401";
;
CDS_LIB"mstr_standard"
BODY_TYPE"PLUMBING"
HDL_TAP"TRUE";
"B \NAC \NWC"8;
"S \NAC"
BN"3"131;
%"TAP"
"1","(-3675,3125)","0","mstr_standard","I402";
;
CDS_LIB"mstr_standard"
BODY_TYPE"PLUMBING"
HDL_TAP"TRUE";
"B \NAC \NWC"8;
"S \NAC"
BN"4"135;
%"TAP"
"1","(-3475,2975)","0","mstr_standard","I403";
;
CDS_LIB"mstr_standard"
BODY_TYPE"PLUMBING"
HDL_TAP"TRUE";
"B \NAC \NWC"9;
"S \NAC"
BN"3"130;
%"TAP"
"1","(-3475,2775)","0","mstr_standard","I404";
;
CDS_LIB"mstr_standard"
BODY_TYPE"PLUMBING"
HDL_TAP"TRUE";
"B \NAC \NWC"9;
"S \NAC"
BN"1"123;
%"TAP"
"1","(-3475,2875)","0","mstr_standard","I405";
;
CDS_LIB"mstr_standard"
BODY_TYPE"PLUMBING"
HDL_TAP"TRUE";
"B \NAC \NWC"9;
"S \NAC"
BN"2"127;
%"TAP"
"1","(-3675,2925)","0","mstr_standard","I406";
;
CDS_LIB"mstr_standard"
BODY_TYPE"PLUMBING"
HDL_TAP"TRUE";
"B \NAC \NWC"8;
"S \NAC"
BN"2"128;
%"TAP"
"1","(-3675,2825)","0","mstr_standard","I407";
;
CDS_LIB"mstr_standard"
BODY_TYPE"PLUMBING"
HDL_TAP"TRUE";
"B \NAC \NWC"8;
"S \NAC"
BN"1"124;
%"TAP"
"1","(-3475,2675)","0","mstr_standard","I408";
;
CDS_LIB"mstr_standard"
BODY_TYPE"PLUMBING"
HDL_TAP"TRUE";
"B \NAC \NWC"9;
"S \NAC"
BN"0"120;
%"TAP"
"1","(-3675,2725)","0","mstr_standard","I409";
;
CDS_LIB"mstr_standard"
BODY_TYPE"PLUMBING"
HDL_TAP"TRUE";
"B \NAC \NWC"8;
"S \NAC"
BN"0"121;
%"SCONN288_DDR506112002KQ"
"2","(-4625,3675)","0","pure_quanta","I410";
;
LOCATION"J21"
$SEC"2"
CDS_SEC"2"
PART_TYPE"SMLF"
VALUE"SCONN288_DDR506112002KQ"
MATERIAL"IO"
CDS_LMAN_SYM_OUTLINE"-600,1150,600,-1150"
NEEDS_NO_SIZE"TRUE"
CDS_LIB"pure_quanta"
PART_NUMBER"DFHST8FS479";
"DQS7_A_C||TDQS7_A_C \B"
$PN"178"170;
"DQS6_A_T||TDQS6_A_T"
$PN"168"116;
"DQS8_B_T||TDQS8_B_T"
$PN"283"117;
"DQS8_B_C||TDQS8_B_C \B"
$PN"282"159;
"DQS7_B_T||TDQS7_B_T"
$PN"272"118;
"DQS0_A_C \B"
$PN"12"163;
"DQS0_A_T"
$PN"11"119;
"DQS0_B_C \B"
$PN"105"120;
"DQS0_B_T"
$PN"104"121;
"DQS1_A_C \B"
$PN"23"122;
"DQS1_A_T"
$PN"22"157;
"DQS1_B_C \B"
$PN"116"123;
"DQS1_B_T"
$PN"115"124;
"DQS2_A_C \B"
$PN"34"125;
"DQS2_A_T"
$PN"33"126;
"DQS2_B_C \B"
$PN"127"127;
"DQS2_B_T"
$PN"126"128;
"DQS3_A_C \B"
$PN"45"129;
"DQS3_A_T"
$PN"44"145;
"DQS3_B_C \B"
$PN"138"130;
"DQS3_B_T"
$PN"137"131;
"DQS4_A_C \B"
$PN"56"132;
"DQS4_A_T"
$PN"55"133;
"DQS4_B_C \B"
$PN"238"134;
"DQS4_B_T"
$PN"239"135;
"DQS5_A_C||TDQS5_A_C||DQS5_A_T||TDQS5_A_T \B"
$PN"156"136;
"DQS5_A_T||TDQS5_A_T"
$PN"157"137;
"DQS5_B_C||TDQS5_B_C \B"
$PN"249"138;
"DQS5_B_T||TDQS5_B_T"
$PN"250"139;
"DQS6_A_C||TDQS6_A_C||DQS6_A_T||TDQS6_A_T \B"
$PN"167"140;
"DQS6_B_C||TDQS6_B_C \B"
$PN"260"141;
"DQS6_B_T||TDQS6_B_T"
$PN"261"142;
"DQS7_A_T||TDQS7_A_T"
$PN"179"143;
"DQS7_B_C||TDQS7_B_C \B"
$PN"271"160;
"DQS8_A_C||TDQS8_A_C \B"
$PN"189"168;
"DQS8_A_T||TDQS8_A_T"
$PN"190"167;
"DQS9_A_C||TDQS9_A_C \B"
$PN"200"169;
"DQS9_A_T||TDQS9_A_T"
$PN"201"166;
"DQS9_B_C||TDQS9_B_C \B"
$PN"94"161;
"DQS9_B_T||TDQS9_B_T||DBI4_B_N"
$PN"93"162;
%"GND"
"1","(-2975,5700)","0","pure_quanta_power","I411";
;
CDS_LIB"pure_quanta_power"
BOM_COST"MEM"
SIZE"1B"
ROOM"MEM_EFGH_DECOUPLING_CAPS"
HDL_POWER"GND";
"A<SIZE-1..0>\NAC"154;
%"Q_CAP"
"1","(-2975,6050)","2","pure_quanta","I412";
;
LOCATION"C151"
$SEC"1"
CDS_SEC"1"
VOLTAGE"25V"
VALUE"10UF"
MATERIAL"X6S"
PACK_TYPE"C0805"
TOLERANCE"10%"
CDS_LIB"pure_quanta"
BOM_COST"MEM"
ROOM""
PART_NUMBER"CH6104KEA00";
"B"
$PN"2"154;
"A"
$PN"1"155;
%"Q_CAP"
"1","(-2400,6050)","2","pure_quanta","I413";
;
LOCATION"C153"
$SEC"1"
CDS_SEC"1"
VALUE"10UF"
PACK_TYPE"C0805"
VOLTAGE"25V"
TOLERANCE"10%"
MATERIAL"X6S"
CDS_LIB"pure_quanta"
BOM_COST"MEM"
ROOM""
PART_NUMBER"CH6104KEA00";
"B"
$PN"2"154;
"A"
$PN"1"155;
%"UNIVERSAL_POWER"
"1","(-2975,6375)","0","pure_quanta_power","I414";
;
HDL_POWER"P12V_MEM_CPU0"
BOM_COST"VR_SYSTEM"
CDS_LIB"pure_quanta_power";
"A"155;
%"Q_RES"
"1","(-8025,2825)","0","pure_quanta","I416";
;
LOCATION"R1572"
$SEC"1"
CDS_SEC"1"
VALUE"49.9"
TOLERANCE"1%"
WATTAGE"1/16W"
PACK_TYPE"0402LF"
MATERIAL"CHIP"
CDS_LIB"pure_quanta"
PART_NUMBER"CS04992FB07";
"B"
$PN"2"16;
"A"
$PN"1"18;
%"Q_RES"
"1","(-8325,3025)","0","pure_quanta","I418";
;
LOCATION"R1678"
$SEC"1"
CDS_SEC"1"
PACK_TYPE"0402LF"
MATERIAL"CHIP"
VALUE"10"
TOLERANCE"1%"
WATTAGE"1/16W"
CDS_LIB"pure_quanta"
PART_NUMBER"CS01002FB07";
"B"
$PN"2"17;
"A"
$PN"1"20;
END.
